# BASEBOARD_FAB2 (Tioga Pass) — schematic netlist excerpt (pin names and nets, part order shuffled) for the footprints in the layout excerpt that follows; sources: Cadence DE-HDL packaged netlist, KiCad conversion of Wiwynn_Tioga_Pass_MB.brd

S8E1  SWITCH_D90553001  IC  pkg SMLF  page 157 : A = GND ; B = FP_NMI_BTN_OUT_R_N
C1A5  CAP_A  0.01UF 25V 10% X7R  pkg 0402V  page 87 : A = M_M_VREF ; B = GND
R1D26  RES  33.2 1% CHIP  pkg 0402  page 199 : A = IRQ_SML1_PMBUS_ALERT_R_N ; B = IRQ_SML1_PMBUS_ALERT_N

(kicad_pcb
	(version 20260206)
	(generator "pcbnew")
	(generator_version "10.0")
	(general
		(thickness 1.6)
		(legacy_teardrops no)
	)
	(paper "A4")
	(title_block
		(title "Wiwynn_Tioga_Pass_MB.brd")
		(comment 1 "Tioga Pass / footprints 1837-1839 of 4770")
	)
	(layers
		(0 "F.Cu" signal "TOP")
		(4 "In1.Cu" signal "L2GND")
		(6 "In2.Cu" signal "L3")
		(8 "In3.Cu" signal "L4GND")
		(10 "In4.Cu" signal "L5")
		(12 "In5.Cu" signal "L6GND")
		(14 "In6.Cu" signal "L7VCC")
		(16 "In7.Cu" signal "L8VCC")
		(18 "In8.Cu" signal "L9GND")
		(20 "In9.Cu" signal "L10")
		(22 "In10.Cu" signal "L11GND")
		(24 "In11.Cu" signal "L12")
		(26 "In12.Cu" signal "L13GND")
		(2 "B.Cu" signal "BOTTOM")
		(9 "F.Adhes" user "F.Adhesive")
		(11 "B.Adhes" user "B.Adhesive")
		(13 "F.Paste" user "Package Geometry/Pastemask Top")
		(15 "B.Paste" user "Package Geometry/Pastemask Bottom")
		(5 "F.SilkS" user "Ref Des/Silkscreen Top")
		(7 "B.SilkS" user "Ref Des/Silkscreen Bottom")
		(1 "F.Mask" user "Board Geometry/Soldermask Top")
		(3 "B.Mask" user "Board Geometry/Soldermask Bottom")
		(17 "Dwgs.User" user "User.Drawings")
		(19 "Cmts.User" user "User.Comments")
		(21 "Eco1.User" user "User.Eco1")
		(23 "Eco2.User" user "User.Eco2")
		(25 "Edge.Cuts" user "Board Geometry/Outline")
		(27 "Margin" user)
		(31 "F.CrtYd" user "Package Geometry/Place Bound Top")
		(29 "B.CrtYd" user "Package Geometry/Place Bound Bottom")
		(35 "F.Fab" user "Ref Des/Assembly Top")
		(33 "B.Fab" user "Ref Des/Assembly Bottom")
	)
	(footprint ""
		(layer "F.Cu")
		(at 30.528768 -149.6568 90)
		(property "Reference" "C1A5"
			(at 0 0 90)
			(layer "F.SilkS")
			(hide yes)
			(effects
				(font
					(size 1.27 1.27)
				)
			)
		)
		(property "Value" ""
			(at 0 0 90)
			(layer "F.Fab")
			(effects
				(font
					(size 1.27 1.27)
				)
			)
		)
		(duplicate_pad_numbers_are_jumpers no)
		(fp_poly
			(pts
				(xy 0.3048 -0.1016) (xy 0.3048 0.9906) (xy -0.3048 0.9906) (xy -0.3048 -0.1016)
			)
			(stroke
				(width 0)
				(type default)
			)
			(fill no)
			(layer "F.CrtYd")
		)
		(fp_line
			(start 0.3048 -0.1016)
			(end -0.3048 -0.1016)
			(stroke
				(width 0.1)
				(type default)
			)
			(layer "F.Fab")
		)
		(fp_line
			(start -0.3048 -0.1016)
			(end -0.3048 0.9906)
			(stroke
				(width 0.1)
				(type default)
			)
			(layer "F.Fab")
		)
		(fp_line
			(start 0.3048 0.9906)
			(end 0.3048 -0.1016)
			(stroke
				(width 0.1)
				(type default)
			)
			(layer "F.Fab")
		)
		(fp_line
			(start -0.3048 0.9906)
			(end 0.3048 0.9906)
			(stroke
				(width 0.1)
				(type default)
			)
			(layer "F.Fab")
		)
		(pad "1" smd rect
			(at 0 0 90)
			(size 0.508 0.508)
			(layers "F.Cu" "F.Mask" "F.Paste")
			(net "M_M_VREF")
		)
		(pad "2" smd rect
			(at 0 0.889 90)
			(size 0.508 0.508)
			(layers "F.Cu" "F.Mask" "F.Paste")
			(net "GND")
		)
		(zone
			(layer "F.Cu")
			(hatch none 0.5)
			(connect_pads
				(clearance 0)
			)
			(min_thickness 0.25)
			(keepout
				(tracks allowed)
				(vias not_allowed)
				(pads allowed)
				(copperpour not_allowed)
				(footprints allowed)
			)
			(placement
				(enabled no)
				(sheetname "")
			)
			(fill
				(thermal_gap 0.5)
				(thermal_bridge_width 0.5)
				(island_removal_mode 0)
			)
			(polygon
				(pts
					(xy 30.782768 -149.4028) (xy 30.782768 -149.9108) (xy 31.163768 -149.9108) (xy 31.163768 -149.4028)
				)
			)
		)
		(zone
			(layer "F.Cu")
			(hatch none 0.5)
			(connect_pads
				(clearance 0)
			)
			(min_thickness 0.25)
			(keepout
				(tracks not_allowed)
				(vias allowed)
				(pads allowed)
				(copperpour not_allowed)
				(footprints allowed)
			)
			(placement
				(enabled no)
				(sheetname "")
			)
			(fill
				(thermal_gap 0.5)
				(thermal_bridge_width 0.5)
				(island_removal_mode 0)
			)
			(polygon
				(pts
					(xy 31.163768 -149.4028) (xy 31.163768 -149.9108) (xy 30.782768 -149.9108) (xy 30.782768 -149.4028)
				)
			)
		)
	)
	(footprint ""
		(layer "F.Cu")
		(at 414.528 -16.383)
		(property "Reference" "S8E1"
			(at -2.31267 3.3274 270)
			(unlocked yes)
			(layer "F.SilkS")
			(effects
				(font
					(size 0.7874 0.5842)
					(thickness 0.1524)
				)
			)
		)
		(property "Value" ""
			(at 0 0 0)
			(layer "F.Fab")
			(effects
				(font
					(size 1.27 1.27)
				)
			)
		)
		(duplicate_pad_numbers_are_jumpers no)
		(fp_line
			(start -1.6256 0.0381)
			(end -0.954278 0.0381)
			(stroke
				(width 0.1524)
				(type default)
			)
			(layer "F.SilkS")
		)
		(fp_line
			(start -1.6256 4.2799)
			(end -1.6256 0.0381)
			(stroke
				(width 0.1524)
				(type default)
			)
			(layer "F.SilkS")
		)
		(fp_line
			(start -1.6256 4.2799)
			(end -0.954024 4.2799)
			(stroke
				(width 0.1524)
				(type default)
			)
			(layer "F.SilkS")
		)
		(fp_line
			(start 1.6256 0.0381)
			(end 0.953262 0.0381)
			(stroke
				(width 0.1524)
				(type default)
			)
			(layer "F.SilkS")
		)
		(fp_line
			(start 1.6256 0.0381)
			(end 1.6256 4.2799)
			(stroke
				(width 0.1524)
				(type default)
			)
			(layer "F.SilkS")
		)
		(fp_line
			(start 1.6256 4.2799)
			(end 0.954024 4.2799)
			(stroke
				(width 0.1524)
				(type default)
			)
			(layer "F.SilkS")
		)
		(fp_circle
			(center -1.177036 -0.999998)
			(end -1.050036 -0.999998)
			(stroke
				(width 0.254)
				(type default)
			)
			(fill no)
			(layer "F.SilkS")
		)
		(fp_poly
			(pts
				(xy -1.6256 0.0381) (xy -1.6256 4.2799) (xy 1.6256 4.2799) (xy 1.6256 0.0381)
			)
			(stroke
				(width 0)
				(type default)
			)
			(fill no)
			(layer "F.CrtYd")
		)
		(fp_line
			(start -1.6256 0.0381)
			(end 1.6256 0.0381)
			(stroke
				(width 0.1)
				(type default)
			)
			(layer "F.Fab")
		)
		(fp_line
			(start -1.6256 4.2799)
			(end -1.6256 0.0381)
			(stroke
				(width 0.1)
				(type default)
			)
			(layer "F.Fab")
		)
		(fp_line
			(start 1.6256 0.0381)
			(end 1.6256 4.2799)
			(stroke
				(width 0.1)
				(type default)
			)
			(layer "F.Fab")
		)
		(fp_line
			(start 1.6256 4.2799)
			(end -1.6256 4.2799)
			(stroke
				(width 0.1)
				(type default)
			)
			(layer "F.Fab")
		)
		(fp_circle
			(center -1.208786 -1.23698)
			(end -1.081786 -1.23698)
			(stroke
				(width 0.254)
				(type default)
			)
			(fill no)
			(layer "F.Fab")
		)
		(pad "1" smd rect
			(at 0 0)
			(size 1.2446 1.7272)
			(layers "F.Cu" "F.Mask" "F.Paste")
			(net "GND")
		)
		(pad "2" smd rect
			(at 0 4.318)
			(size 1.2446 1.7272)
			(layers "F.Cu" "F.Mask" "F.Paste")
			(net "FP_NMI_BTN_OUT_R_N")
		)
	)
	(footprint ""
		(layer "F.Cu")
		(at 17.9832 -79.6417 180)
		(property "Reference" "R1D26"
			(at 0 0 180)
			(layer "F.SilkS")
			(hide yes)
			(effects
				(font
					(size 1.27 1.27)
				)
			)
		)
		(property "Value" ""
			(at 0 0 180)
			(layer "F.Fab")
			(effects
				(font
					(size 1.27 1.27)
				)
			)
		)
		(duplicate_pad_numbers_are_jumpers no)
		(fp_poly
			(pts
				(xy -0.2794 -0.1016) (xy 0.2794 -0.1016) (xy 0.2794 0.9906) (xy -0.2794 0.9906)
			)
			(stroke
				(width 0)
				(type default)
			)
			(fill no)
			(layer "F.CrtYd")
		)
		(fp_line
			(start 0.2794 0.9906)
			(end 0.2794 -0.1016)
			(stroke
				(width 0.1)
				(type default)
			)
			(layer "F.Fab")
		)
		(fp_line
			(start 0.2794 -0.1016)
			(end -0.2794 -0.1016)
			(stroke
				(width 0.1)
				(type default)
			)
			(layer "F.Fab")
		)
		(fp_line
			(start -0.2794 0.9906)
			(end 0.2794 0.9906)
			(stroke
				(width 0.1)
				(type default)
			)
			(layer "F.Fab")
		)
		(fp_line
			(start -0.2794 -0.1016)
			(end -0.2794 0.9906)
			(stroke
				(width 0.1)
				(type default)
			)
			(layer "F.Fab")
		)
		(pad "1" smd rect
			(at 0 0 180)
			(size 0.508 0.508)
			(layers "F.Cu" "F.Mask" "F.Paste")
			(net "IRQ_SML1_PMBUS_ALERT_R_N")
		)
		(pad "2" smd rect
			(at 0 0.889 180)
			(size 0.508 0.508)
			(layers "F.Cu" "F.Mask" "F.Paste")
			(net "IRQ_SML1_PMBUS_ALERT_N")
		)
		(zone
			(layer "F.Cu")
			(hatch none 0.5)
			(connect_pads
				(clearance 0)
			)
			(min_thickness 0.25)
			(keepout
				(tracks not_allowed)
				(vias allowed)
				(pads allowed)
				(copperpour not_allowed)
				(footprints allowed)
			)
			(placement
				(enabled no)
				(sheetname "")
			)
			(fill
				(thermal_gap 0.5)
				(thermal_bridge_width 0.5)
				(island_removal_mode 0)
			)
			(polygon
				(pts
					(xy 18.2372 -80.2767) (xy 17.7292 -80.2767) (xy 17.7292 -79.8957) (xy 18.2372 -79.8957)
				)
			)
		)
		(zone
			(layer "F.Cu")
			(hatch none 0.5)
			(connect_pads
				(clearance 0)
			)
			(min_thickness 0.25)
			(keepout
				(tracks allowed)
				(vias not_allowed)
				(pads allowed)
				(copperpour not_allowed)
				(footprints allowed)
			)
			(placement
				(enabled no)
				(sheetname "")
			)
			(fill
				(thermal_gap 0.5)
				(thermal_bridge_width 0.5)
				(island_removal_mode 0)
			)
			(polygon
				(pts
					(xy 18.2372 -79.8957) (xy 17.7292 -79.8957) (xy 17.7292 -80.2767) (xy 18.2372 -80.2767)
				)
			)
		)
	)
)
